(kicad_pcb
	(version 20241229)
	(generator "pcbnew")
	(generator_version "9.0")
	(general
		(thickness 1.6296)
		(legacy_teardrops no)
	)
	(paper "A3")
	(title_block
		(title "Thunderbolt to 10GbE adapter")
		(date "2026-04-21")
		(rev "1.1.0")
		(company "Antmicro Ltd")
		(comment 1 "www.antmicro.com")
		(comment 9 "footprint 288 of 703 (U14), pads 245-323 of 503")
	)
	(layers
		(0 "F.Cu" signal)
		(4 "In1.Cu" signal)
		(6 "In2.Cu" signal)
		(8 "In3.Cu" signal)
		(10 "In4.Cu" signal)
		(12 "In5.Cu" signal)
		(14 "In6.Cu" signal)
		(2 "B.Cu" signal)
		(9 "F.Adhes" user "F.Adhesive")
		(11 "B.Adhes" user "B.Adhesive")
		(13 "F.Paste" user)
		(15 "B.Paste" user)
		(5 "F.SilkS" user "F.Silkscreen")
		(7 "B.SilkS" user "B.Silkscreen")
		(1 "F.Mask" user)
		(3 "B.Mask" user)
		(17 "Dwgs.User" user "User.Drawings")
		(19 "Cmts.User" user "User.Comments")
		(21 "Eco1.User" user "User.Eco1")
		(23 "Eco2.User" user "User.Eco2")
		(25 "Edge.Cuts" user)
		(27 "Margin" user)
		(31 "F.CrtYd" user "F.Courtyard")
		(29 "B.CrtYd" user "B.Courtyard")
		(35 "F.Fab" user)
		(33 "B.Fab" user)
	)
	(footprint "antmicro-footprints:FCBGA-503_22x22mm_Layout21x24_P1mm"
		(layer "F.Cu")
		(at 151.005 81.499999 -90)
		(property "Reference" "U14"
			(at -11.499999 11.005 0)
			(layer "F.SilkS")
			(effects
				(font
					(size 0.7 0.7)
					(thickness 0.15)
				)
				(justify left bottom)
			)
		)
		(property "Value" "EZX710AT2_S_LMR5"
			(at -11.4 12.5 270)
			(layer "F.Fab")
			(effects
				(font
					(size 0.7 0.7)
					(thickness 0.15)
				)
				(justify left bottom)
			)
		)
		(property "Datasheet" "https://www.google.com/url?sa=t&source=web&rct=j&opi=89978449&url=https://cdrdv2-public.intel.com/596333/596333_X710-TM4_Datasheet_v_2_4.pdf&ved=2ahUKEwiSuv20_sCOAxXVCRAIHdxGO_UQFnoECBEQAQ&usg=AOvVaw1CjGyrGWE8ZvOdw4VBsY6U"
			(at 0 0 270)
			(layer "F.Fab")
			(effects
				(font
					(size 0.7 0.7)
					(thickness 0.15)
				)
				(justify left bottom)
			)
		)
		(property "Description" "Ethernet ICs Intel Ethernet Controller 10 Gigabit X7"
			(at 0 0 270)
			(layer "F.Fab")
			(effects
				(font
					(size 0.7 0.7)
					(thickness 0.15)
				)
				(justify left bottom)
			)
		)
		(property "MPN" "EZX710AT2 S LMR5"
			(at 0 0 270)
			(unlocked yes)
			(layer "F.Fab")
			(hide yes)
			(effects
				(font
					(size 1 1)
					(thickness 0.15)
				)
			)
		)
		(property "Manufacturer" "Intel"
			(at 0 0 270)
			(unlocked yes)
			(layer "F.Fab")
			(hide yes)
			(effects
				(font
					(size 1 1)
					(thickness 0.15)
				)
			)
		)
		(property "Author" "Antmicro"
			(at 0 0 270)
			(unlocked yes)
			(layer "F.Fab")
			(hide yes)
			(effects
				(font
					(size 1 1)
					(thickness 0.15)
				)
			)
		)
		(property "License" "Apache-2.0"
			(at 0 0 270)
			(unlocked yes)
			(layer "F.Fab")
			(hide yes)
			(effects
				(font
					(size 1 1)
					(thickness 0.15)
				)
			)
		)
		(sheetname "/X710-AT2 power/")
		(sheetfile "x710-at2-power.kicad_sch")
		(attr smd)
		(pad "H30" smd circle
			(at 4.25 -3.895 270)
			(size 0.5 0.5)
			(layers "F.Cu" "F.Mask" "F.Paste")
			(net 23 "GND")
			(pinfunction "VSSA")
			(pintype "passive")
		)
		(pad "H32" smd circle
			(at 5.25 -3.895 270)
			(size 0.5 0.5)
			(layers "F.Cu" "F.Mask" "F.Paste")
			(net 23 "GND")
			(pinfunction "VSSA")
			(pintype "passive")
		)
		(pad "H34" smd circle
			(at 6.25 -3.895 270)
			(size 0.5 0.5)
			(layers "F.Cu" "F.Mask" "F.Paste")
			(net 23 "GND")
			(pinfunction "VSSA")
			(pintype "passive")
		)
		(pad "H36" smd circle
			(at 7.25 -3.895 270)
			(size 0.5 0.5)
			(layers "F.Cu" "F.Mask" "F.Paste")
			(net 23 "GND")
			(pinfunction "VSSA")
			(pintype "passive")
		)
		(pad "H38" smd circle
			(at 8.25 -3.895 270)
			(size 0.5 0.5)
			(layers "F.Cu" "F.Mask" "F.Paste")
			(net 23 "GND")
			(pinfunction "VSSA")
			(pintype "passive")
		)
		(pad "H40" smd circle
			(at 9.25 -3.895 270)
			(size 0.5 0.5)
			(layers "F.Cu" "F.Mask" "F.Paste")
			(net 23 "GND")
			(pinfunction "RSVDH40_VSS")
			(pintype "passive")
		)
		(pad "H42" smd circle
			(at 10.25 -3.895 270)
			(size 0.5 0.5)
			(layers "F.Cu" "F.Mask" "F.Paste")
			(net 453 "unconnected-(U14F-XTAL_PTP_XTAL_N-PadH42)")
			(pinfunction "XTAL_PTP_XTAL_N")
			(pintype "passive+no_connect")
		)
		(pad "J1" smd circle
			(at -10.25 -3.03 270)
			(size 0.5 0.5)
			(layers "F.Cu" "F.Mask" "F.Paste")
			(net 442 "Net-(U14D-NCSI_RXD_0)")
			(pinfunction "NCSI_RXD_0")
			(pintype "output")
		)
		(pad "J3" smd circle
			(at -9.25 -3.03 270)
			(size 0.5 0.5)
			(layers "F.Cu" "F.Mask" "F.Paste")
			(net 443 "Net-(U14D-NCSI_RXD_1)")
			(pinfunction "NCSI_RXD_1")
			(pintype "output")
		)
		(pad "J5" smd circle
			(at -8.25 -3.03 270)
			(size 0.5 0.5)
			(layers "F.Cu" "F.Mask" "F.Paste")
			(net 441 "Net-(U14D-NCSI_CRS_DV)")
			(pinfunction "NCSI_CRS_DV")
			(pintype "output")
		)
		(pad "J7" smd circle
			(at -7.25 -3.03 270)
			(size 0.5 0.5)
			(layers "F.Cu" "F.Mask" "F.Paste")
			(net 468 "unconnected-(U14C-SDP2_1-PadJ7)")
			(pinfunction "SDP2_1")
			(pintype "passive+no_connect")
		)
		(pad "J9" smd circle
			(at -6.25 -3.03 270)
			(size 0.5 0.5)
			(layers "F.Cu" "F.Mask" "F.Paste")
			(net 64 "/X710-AT2 10GbE/OSC_SEL")
			(pinfunction "OSC_SEL")
			(pintype "tri_state")
		)
		(pad "J11" smd circle
			(at -5.25 -3.03 270)
			(size 0.5 0.5)
			(layers "F.Cu" "F.Mask" "F.Paste")
			(net 87 "/X710-AT2 Misc/RSVD_J11_VSS")
			(pinfunction "RSVD_J11_VSS")
			(pintype "passive")
		)
		(pad "J13" smd circle
			(at -4.25 -3.03 270)
			(size 0.5 0.5)
			(layers "F.Cu" "F.Mask" "F.Paste")
			(net 23 "GND")
			(pinfunction "RSVDJ13_VSS")
			(pintype "passive")
		)
		(pad "J15" smd circle
			(at -3.25 -3.03 270)
			(size 0.5 0.5)
			(layers "F.Cu" "F.Mask" "F.Paste")
			(net 534 "unconnected-(U14F-RSVDJ15_NC-PadJ15)")
			(pinfunction "RSVDJ15_NC")
			(pintype "passive+no_connect")
		)
		(pad "J17" smd circle
			(at -2.25 -3.03 270)
			(size 0.5 0.5)
			(layers "F.Cu" "F.Mask" "F.Paste")
			(net 23 "GND")
			(pinfunction "RSVDJ17_VSS")
			(pintype "passive")
		)
		(pad "J19" smd circle
			(at -1.25 -3.03 270)
			(size 0.5 0.5)
			(layers "F.Cu" "F.Mask" "F.Paste")
			(net 23 "GND")
			(pinfunction "RSVDJ19_VSS")
			(pintype "passive")
		)
		(pad "J21" smd circle
			(at -0.25 -3.03 270)
			(size 0.5 0.5)
			(layers "F.Cu" "F.Mask" "F.Paste")
			(net 23 "GND")
			(pinfunction "RSVDJ21_VSS")
			(pintype "passive")
		)
		(pad "J23" smd circle
			(at 0.75 -3.03 270)
			(size 0.5 0.5)
			(layers "F.Cu" "F.Mask" "F.Paste")
			(net 556 "unconnected-(U14E-RSVDJ23_NC-PadJ23)")
			(pinfunction "RSVDJ23_NC")
			(pintype "passive+no_connect")
		)
		(pad "J25" smd circle
			(at 1.75 -3.03 270)
			(size 0.5 0.5)
			(layers "F.Cu" "F.Mask" "F.Paste")
			(net 480 "unconnected-(U14E-RSVDJ25_NC-PadJ25)")
			(pinfunction "RSVDJ25_NC")
			(pintype "passive+no_connect")
		)
		(pad "J27" smd circle
			(at 2.75 -3.03 270)
			(size 0.5 0.5)
			(layers "F.Cu" "F.Mask" "F.Paste")
			(net 12 "XFI_VDD")
			(pinfunction "XFI_VDD")
			(pintype "power_in")
		)
		(pad "J29" smd circle
			(at 3.75 -3.03 270)
			(size 0.5 0.5)
			(layers "F.Cu" "F.Mask" "F.Paste")
			(net 12 "XFI_VDD")
			(pinfunction "XFI_VDD")
			(pintype "passive")
		)
		(pad "J31" smd circle
			(at 4.75 -3.03 270)
			(size 0.5 0.5)
			(layers "F.Cu" "F.Mask" "F.Paste")
			(net 12 "XFI_VDD")
			(pinfunction "XFI_VDD")
			(pintype "passive")
		)
		(pad "J33" smd circle
			(at 5.75 -3.03 270)
			(size 0.5 0.5)
			(layers "F.Cu" "F.Mask" "F.Paste")
			(net 21 "XFI_PVDD")
			(pinfunction "XFI_PVDD")
			(pintype "power_in")
		)
		(pad "J35" smd circle
			(at 6.75 -3.03 270)
			(size 0.5 0.5)
			(layers "F.Cu" "F.Mask" "F.Paste")
			(net 12 "XFI_VDD")
			(pinfunction "XFI_VDD")
			(pintype "passive")
		)
		(pad "J37" smd circle
			(at 7.75 -3.03 270)
			(size 0.5 0.5)
			(layers "F.Cu" "F.Mask" "F.Paste")
			(net 62 "/X710-AT2 10GbE/RESCAL_RES_P")
			(pinfunction "RESCAL_RES_P")
			(pintype "passive")
		)
		(pad "J39" smd circle
			(at 8.75 -3.03 270)
			(size 0.5 0.5)
			(layers "F.Cu" "F.Mask" "F.Paste")
			(net 528 "unconnected-(U14G-RSVDJ39_NC-PadJ39)")
			(pinfunction "RSVDJ39_NC")
			(pintype "passive+no_connect")
		)
		(pad "J41" smd circle
			(at 9.75 -3.03 270)
			(size 0.5 0.5)
			(layers "F.Cu" "F.Mask" "F.Paste")
			(net 526 "unconnected-(U14F-XTAL_PTP_XTAL_P-PadJ41)")
			(pinfunction "XTAL_PTP_XTAL_P")
			(pintype "passive+no_connect")
		)
		(pad "K2" smd circle
			(at -9.75 -2.165 270)
			(size 0.5 0.5)
			(layers "F.Cu" "F.Mask" "F.Paste")
			(net 71 "/X710-AT2 10GbE/MDIO3_SDA3")
			(pinfunction "MDIO3_SDA3")
			(pintype "passive")
		)
		(pad "K4" smd circle
			(at -8.75 -2.165 270)
			(size 0.5 0.5)
			(layers "F.Cu" "F.Mask" "F.Paste")
			(net 70 "/X710-AT2 10GbE/MDC3_SCL3")
			(pinfunction "MDC3_SCL3")
			(pintype "passive")
		)
		(pad "K6" smd circle
			(at -7.75 -2.165 270)
			(size 0.5 0.5)
			(layers "F.Cu" "F.Mask" "F.Paste")
			(net 123 "/X710-AT2 10GbE/~{P1_INT_R}")
			(pinfunction "SDP0_2")
			(pintype "tri_state")
		)
		(pad "K8" smd circle
			(at -6.75 -2.165 270)
			(size 0.5 0.5)
			(layers "F.Cu" "F.Mask" "F.Paste")
			(net 23 "GND")
			(pinfunction "VSSA")
			(pintype "passive")
		)
		(pad "K10" smd circle
			(at -5.75 -2.165 270)
			(size 0.5 0.5)
			(layers "F.Cu" "F.Mask" "F.Paste")
			(net 23 "GND")
			(pinfunction "VSSA")
			(pintype "passive")
		)
		(pad "K12" smd circle
			(at -4.75 -2.165 270)
			(size 0.5 0.5)
			(layers "F.Cu" "F.Mask" "F.Paste")
			(net 23 "GND")
			(pinfunction "VSSA")
			(pintype "passive")
		)
		(pad "K14" smd circle
			(at -3.75 -2.165 270)
			(size 0.5 0.5)
			(layers "F.Cu" "F.Mask" "F.Paste")
			(net 23 "GND")
			(pinfunction "VSSA")
			(pintype "passive")
		)
		(pad "K16" smd circle
			(at -2.75 -2.165 270)
			(size 0.5 0.5)
			(layers "F.Cu" "F.Mask" "F.Paste")
			(net 23 "GND")
			(pinfunction "VSSA")
			(pintype "passive")
		)
		(pad "K18" smd circle
			(at -1.75 -2.165 270)
			(size 0.5 0.5)
			(layers "F.Cu" "F.Mask" "F.Paste")
			(net 23 "GND")
			(pinfunction "VSS")
			(pintype "passive")
		)
		(pad "K20" smd circle
			(at -0.75 -2.165 270)
			(size 0.5 0.5)
			(layers "F.Cu" "F.Mask" "F.Paste")
			(net 23 "GND")
			(pinfunction "VSS")
			(pintype "passive")
		)
		(pad "K22" smd circle
			(at 0.25 -2.165 270)
			(size 0.5 0.5)
			(layers "F.Cu" "F.Mask" "F.Paste")
			(net 540 "unconnected-(U14E-RSVDK22_NC-PadK22)")
			(pinfunction "RSVDK22_NC")
			(pintype "passive+no_connect")
		)
		(pad "K24" smd circle
			(at 1.25 -2.165 270)
			(size 0.5 0.5)
			(layers "F.Cu" "F.Mask" "F.Paste")
			(net 499 "unconnected-(U14E-RSVDK24_NC-PadK24)")
			(pinfunction "RSVDK24_NC")
			(pintype "passive+no_connect")
		)
		(pad "K26" smd circle
			(at 2.25 -2.165 270)
			(size 0.5 0.5)
			(layers "F.Cu" "F.Mask" "F.Paste")
			(net 585 "unconnected-(U14G-RSVDK26_NC-PadK26)")
			(pinfunction "RSVDK26_NC")
			(pintype "passive+no_connect")
		)
		(pad "K28" smd circle
			(at 3.25 -2.165 270)
			(size 0.5 0.5)
			(layers "F.Cu" "F.Mask" "F.Paste")
			(net 466 "unconnected-(U14G-RSVDK28_NC-PadK28)")
			(pinfunction "RSVDK28_NC")
			(pintype "passive+no_connect")
		)
		(pad "K30" smd circle
			(at 4.25 -2.165 270)
			(size 0.5 0.5)
			(layers "F.Cu" "F.Mask" "F.Paste")
			(net 470 "unconnected-(U14F-RSVDK30_NC-PadK30)")
			(pinfunction "RSVDK30_NC")
			(pintype "passive+no_connect")
		)
		(pad "K32" smd circle
			(at 5.25 -2.165 270)
			(size 0.5 0.5)
			(layers "F.Cu" "F.Mask" "F.Paste")
			(net 546 "unconnected-(U14F-RSVDK32_NC-PadK32)")
			(pinfunction "RSVDK32_NC")
			(pintype "passive+no_connect")
		)
		(pad "K34" smd circle
			(at 6.25 -2.165 270)
			(size 0.5 0.5)
			(layers "F.Cu" "F.Mask" "F.Paste")
			(net 498 "unconnected-(U14G-RSVDK34_NC-PadK34)")
			(pinfunction "RSVDK34_NC")
			(pintype "passive+no_connect")
		)
		(pad "K36" smd circle
			(at 7.25 -2.165 270)
			(size 0.5 0.5)
			(layers "F.Cu" "F.Mask" "F.Paste")
			(net 476 "unconnected-(U14G-RSVDK36_NC-PadK36)")
			(pinfunction "RSVDK36_NC")
			(pintype "passive+no_connect")
		)
		(pad "K38" smd circle
			(at 8.25 -2.165 270)
			(size 0.5 0.5)
			(layers "F.Cu" "F.Mask" "F.Paste")
			(net 23 "GND")
			(pinfunction "VSSA")
			(pintype "passive")
		)
		(pad "K40" smd circle
			(at 9.25 -2.165 270)
			(size 0.5 0.5)
			(layers "F.Cu" "F.Mask" "F.Paste")
			(net 85 "/X710-AT2 Misc/RSVDK40_1P88V")
			(pinfunction "RSVDK40_1P88V")
			(pintype "passive")
		)
		(pad "K42" smd circle
			(at 10.25 -2.165 270)
			(size 0.5 0.5)
			(layers "F.Cu" "F.Mask" "F.Paste")
			(net 23 "GND")
			(pinfunction "RSVDK42_VSS")
			(pintype "passive")
		)
		(pad "L1" smd circle
			(at -10.25 -1.3 270)
			(size 0.5 0.5)
			(layers "F.Cu" "F.Mask" "F.Paste")
			(net 76 "/X710-AT2 10GbE/MDIO2_SDA2")
			(pinfunction "MDIO2_SDA2")
			(pintype "passive")
		)
		(pad "L3" smd circle
			(at -9.25 -1.3 270)
			(size 0.5 0.5)
			(layers "F.Cu" "F.Mask" "F.Paste")
			(net 72 "/X710-AT2 10GbE/MDC2_SCL2")
			(pinfunction "MDC2_SCL2")
			(pintype "passive")
		)
		(pad "L5" smd circle
			(at -8.25 -1.3 270)
			(size 0.5 0.5)
			(layers "F.Cu" "F.Mask" "F.Paste")
			(net 580 "unconnected-(U14C-SDP0_3-PadL5)")
			(pinfunction "SDP0_3")
			(pintype "passive+no_connect")
		)
		(pad "L7" smd circle
			(at -7.25 -1.3 270)
			(size 0.5 0.5)
			(layers "F.Cu" "F.Mask" "F.Paste")
			(net 82 "/X710-AT2 Misc/GPIO5_POR_BYPASS")
			(pinfunction "GPIO_5")
			(pintype "tri_state")
		)
		(pad "L9" smd circle
			(at -6.25 -1.3 270)
			(size 0.5 0.5)
			(layers "F.Cu" "F.Mask" "F.Paste")
			(net 7 "+3V3")
			(pinfunction "VCC3P3_TX")
			(pintype "power_in")
		)
		(pad "L11" smd circle
			(at -5.25 -1.3 270)
			(size 0.5 0.5)
			(layers "F.Cu" "F.Mask" "F.Paste")
			(net 1 "VCCA")
			(pinfunction "VCCA")
			(pintype "power_in")
		)
		(pad "L13" smd circle
			(at -4.25 -1.3 270)
			(size 0.5 0.5)
			(layers "F.Cu" "F.Mask" "F.Paste")
			(net 1 "VCCA")
			(pinfunction "VCCA")
			(pintype "passive")
		)
		(pad "L15" smd circle
			(at -3.25 -1.3 270)
			(size 0.5 0.5)
			(layers "F.Cu" "F.Mask" "F.Paste")
			(net 1 "VCCA")
			(pinfunction "VCCA")
			(pintype "passive")
		)
		(pad "L17" smd circle
			(at -2.25 -1.3 270)
			(size 0.5 0.5)
			(layers "F.Cu" "F.Mask" "F.Paste")
			(net 1 "VCCA")
			(pinfunction "VCCA")
			(pintype "passive")
		)
		(pad "L19" smd circle
			(at -1.25 -1.3 270)
			(size 0.5 0.5)
			(layers "F.Cu" "F.Mask" "F.Paste")
			(net 9 "VCCD")
			(pinfunction "VCCD")
			(pintype "power_in")
		)
		(pad "L21" smd circle
			(at -0.25 -1.3 270)
			(size 0.5 0.5)
			(layers "F.Cu" "F.Mask" "F.Paste")
			(net 9 "VCCD")
			(pinfunction "VCCD")
			(pintype "passive")
		)
		(pad "L23" smd circle
			(at 0.75 -1.3 270)
			(size 0.5 0.5)
			(layers "F.Cu" "F.Mask" "F.Paste")
			(net 542 "unconnected-(U14E-RSVDL23_NC-PadL23)")
			(pinfunction "RSVDL23_NC")
			(pintype "passive+no_connect")
		)
		(pad "L25" smd circle
			(at 1.75 -1.3 270)
			(size 0.5 0.5)
			(layers "F.Cu" "F.Mask" "F.Paste")
			(net 515 "unconnected-(U14E-RSVDL25_NC-PadL25)")
			(pinfunction "RSVDL25_NC")
			(pintype "passive+no_connect")
		)
		(pad "L27" smd circle
			(at 2.75 -1.3 270)
			(size 0.5 0.5)
			(layers "F.Cu" "F.Mask" "F.Paste")
			(net 505 "unconnected-(U14E-RSVDL27_NC-PadL27)")
			(pinfunction "RSVDL27_NC")
			(pintype "passive+no_connect")
		)
		(pad "L29" smd circle
			(at 3.75 -1.3 270)
			(size 0.5 0.5)
			(layers "F.Cu" "F.Mask" "F.Paste")
			(net 521 "unconnected-(U14G-RSVDL29_NC-PadL29)")
			(pinfunction "RSVDL29_NC")
			(pintype "passive+no_connect")
		)
		(pad "L31" smd circle
			(at 4.75 -1.3 270)
			(size 0.5 0.5)
			(layers "F.Cu" "F.Mask" "F.Paste")
			(net 23 "GND")
			(pinfunction "RSVDL31_VSS")
			(pintype "passive")
		)
		(pad "L33" smd circle
			(at 5.75 -1.3 270)
			(size 0.5 0.5)
			(layers "F.Cu" "F.Mask" "F.Paste")
			(net 84 "/X710-AT2 Misc/RSVDL33")
			(pinfunction "RSVDL33")
			(pintype "passive")
		)
		(pad "L35" smd circle
			(at 6.75 -1.3 270)
			(size 0.5 0.5)
			(layers "F.Cu" "F.Mask" "F.Paste")
			(net 484 "unconnected-(U14F-RSVDL35_NC-PadL35)")
			(pinfunction "RSVDL35_NC")
			(pintype "passive+no_connect")
		)
		(pad "L37" smd circle
			(at 7.75 -1.3 270)
			(size 0.5 0.5)
			(layers "F.Cu" "F.Mask" "F.Paste")
			(net 23 "GND")
			(pinfunction "RSVDL37_VSS")
			(pintype "passive")
		)
		(pad "L39" smd circle
			(at 8.75 -1.3 270)
			(size 0.5 0.5)
			(layers "F.Cu" "F.Mask" "F.Paste")
			(net 18 "+1V88")
			(pinfunction "VDDIO2")
			(pintype "power_in")
		)
		(pad "L41" smd circle
			(at 9.75 -1.3 270)
			(size 0.5 0.5)
			(layers "F.Cu" "F.Mask" "F.Paste")
			(net 148 "/X710-AT2 Misc/MDIO.MDC")
			(pinfunction "MDC")
			(pintype "input")
		)
		(pad "M2" smd circle
			(at -9.75 -0.435 270)
			(size 0.5 0.5)
			(layers "F.Cu" "F.Mask" "F.Paste")
			(net 78 "/X710-AT2 10GbE/MDIO1_SDA1")
			(pinfunction "MDIO1_SDA1")
			(pintype "passive")
		)
		(pad "M4" smd circle
			(at -8.75 -0.435 270)
			(size 0.5 0.5)
			(layers "F.Cu" "F.Mask" "F.Paste")
			(net 77 "/X710-AT2 10GbE/MDC1_SCL1")
			(pinfunction "MDC1_SCL1")
			(pintype "passive")
		)
		(pad "M6" smd circle
			(at -7.75 -0.435 270)
			(size 0.5 0.5)
			(layers "F.Cu" "F.Mask" "F.Paste")
			(net 495 "unconnected-(U14C-SDP3_2-PadM6)")
			(pinfunction "SDP3_2")
			(pintype "passive+no_connect")
		)
		(pad "M8" smd circle
			(at -6.75 -0.435 270)
			(size 0.5 0.5)
			(layers "F.Cu" "F.Mask" "F.Paste")
			(net 513 "unconnected-(U14C-SDP3_3-PadM8)")
			(pinfunction "SDP3_3")
			(pintype "passive+no_connect")
		)
		(pad "M10" smd circle
			(at -5.75 -0.435 270)
			(size 0.5 0.5)
			(layers "F.Cu" "F.Mask" "F.Paste")
			(net 23 "GND")
			(pinfunction "VSSA")
			(pintype "passive")
		)
		(pad "M12" smd circle
			(at -4.75 -0.435 270)
			(size 0.5 0.5)
			(layers "F.Cu" "F.Mask" "F.Paste")
			(net 23 "GND")
			(pinfunction "VSSA")
			(pintype "passive")
		)
		(pad "M14" smd circle
			(at -3.75 -0.435 270)
			(size 0.5 0.5)
			(layers "F.Cu" "F.Mask" "F.Paste")
			(net 23 "GND")
			(pinfunction "VSSA")
			(pintype "passive")
		)
		(pad "M16" smd circle
			(at -2.75 -0.435 270)
			(size 0.5 0.5)
			(layers "F.Cu" "F.Mask" "F.Paste")
			(net 23 "GND")
			(pinfunction "VSSA")
			(pintype "passive")
		)
		(pad "M18" smd circle
			(at -1.75 -0.435 270)
			(size 0.5 0.5)
			(layers "F.Cu" "F.Mask" "F.Paste")
			(net 23 "GND")
			(pinfunction "VSS")
			(pintype "passive")
		)
	)
)
